# S9S_MB_2U (Grand Teton) — schematic netlist excerpt (pin names and nets, part order shuffled) for the footprints in the layout excerpt that follows; sources: Cadence DE-HDL packaged netlist, KiCad conversion of 03242023_DA0F0TMBIJ0_F0T_Motherboard_J_brd_V01_OCP.brd

PR3837  Q_RES  17.4K 1% CHIP  pkg 0402LF  page 157 : A = P12V_OCP_IMON_1 ; B = GND
R2368  Q_RES  150 1% CHIP  pkg 0402LF  page 266 : A = SVID_CLK0_CPU0_R ; B = SVID_CLK_PVCCIN_CPU0_R
C563  Q_CAP  10UF 25V 10% X6S  pkg C0805  page 221 : A = P3V3_AUX_BMC_D ; B = GND

(kicad_pcb
	(version 20260206)
	(generator "pcbnew")
	(generator_version "10.0")
	(general
		(thickness 1.6)
		(legacy_teardrops no)
	)
	(paper "A4")
	(title_block
		(title "03242023_DA0F0TMBIJ0_F0T_Motherboard_J_brd_V01_OCP.brd")
		(comment 1 "Grand Teton / footprints 711-713 of 6105")
	)
	(layers
		(0 "F.Cu" signal "TOP")
		(4 "In1.Cu" signal "GND")
		(6 "In2.Cu" signal "IN1")
		(8 "In3.Cu" signal "GND1")
		(10 "In4.Cu" signal "IN2")
		(12 "In5.Cu" signal "GND2")
		(14 "In6.Cu" signal "IN3")
		(16 "In7.Cu" signal "GND3")
		(18 "In8.Cu" signal "VCC")
		(20 "In9.Cu" signal "VCC1")
		(22 "In10.Cu" signal "GND4")
		(24 "In11.Cu" signal "IN4")
		(26 "In12.Cu" signal "GND5")
		(28 "In13.Cu" signal "IN5")
		(30 "In14.Cu" signal "GND6")
		(32 "In15.Cu" signal "IN6")
		(34 "In16.Cu" signal "GND7")
		(2 "B.Cu" signal "BOTTOM")
		(9 "F.Adhes" user "F.Adhesive")
		(11 "B.Adhes" user "B.Adhesive")
		(13 "F.Paste" user "Package Geometry/Pastemask Top")
		(15 "B.Paste" user "Package Geometry/Pastemask Bottom")
		(5 "F.SilkS" user "Ref Des/Silkscreen Top")
		(7 "B.SilkS" user "Ref Des/Silkscreen Bottom")
		(1 "F.Mask" user "Board Geometry/Soldermask Top")
		(3 "B.Mask" user "Board Geometry/Soldermask Bottom")
		(17 "Dwgs.User" user "User.Drawings")
		(19 "Cmts.User" user "User.Comments")
		(21 "Eco1.User" user "User.Eco1")
		(23 "Eco2.User" user "User.Eco2")
		(25 "Edge.Cuts" user "Board Geometry/Outline")
		(27 "Margin" user)
		(31 "F.CrtYd" user "Package Geometry/Place Bound Top")
		(29 "B.CrtYd" user "Package Geometry/Place Bound Bottom")
		(35 "F.Fab" user "Ref Des/Assembly Top")
		(33 "B.Fab" user "Ref Des/Assembly Bottom")
	)
	(footprint ""
		(layer "F.Cu")
		(at 350.78416 -357.562658)
		(property "Reference" "R2368"
			(at 0 0 0)
			(layer "F.SilkS")
			(hide yes)
			(effects
				(font
					(size 1.27 1.27)
				)
			)
		)
		(property "Value" ""
			(at 0 0 0)
			(layer "F.Fab")
			(effects
				(font
					(size 1.27 1.27)
				)
			)
		)
		(duplicate_pad_numbers_are_jumpers no)
		(fp_line
			(start -0.7874 -0.4064)
			(end 0.7874 -0.4064)
			(stroke
				(width 0.1524)
				(type default)
			)
			(layer "F.SilkS")
		)
		(fp_line
			(start -0.7874 0.4064)
			(end -0.7874 -0.4064)
			(stroke
				(width 0.1524)
				(type default)
			)
			(layer "F.SilkS")
		)
		(fp_line
			(start 0.7874 -0.4064)
			(end 0.7874 0.4064)
			(stroke
				(width 0.1524)
				(type default)
			)
			(layer "F.SilkS")
		)
		(fp_line
			(start 0.7874 0.4064)
			(end -0.7874 0.4064)
			(stroke
				(width 0.1524)
				(type default)
			)
			(layer "F.SilkS")
		)
		(fp_line
			(start -0.67945 -0.305054)
			(end -0.12065 -0.305054)
			(stroke
				(width 0.1)
				(type default)
			)
			(layer "F.Fab")
		)
		(fp_line
			(start -0.67945 0.3048)
			(end -0.67945 -0.305054)
			(stroke
				(width 0.1)
				(type default)
			)
			(layer "F.Fab")
		)
		(fp_line
			(start -0.12065 -0.305054)
			(end -0.12065 -0.2794)
			(stroke
				(width 0.1)
				(type default)
			)
			(layer "F.Fab")
		)
		(fp_line
			(start -0.12065 -0.2794)
			(end 0.12065 -0.2794)
			(stroke
				(width 0.1)
				(type default)
			)
			(layer "F.Fab")
		)
		(fp_line
			(start -0.12065 0.2794)
			(end -0.12065 0.3048)
			(stroke
				(width 0.1)
				(type default)
			)
			(layer "F.Fab")
		)
		(fp_line
			(start -0.12065 0.3048)
			(end -0.67945 0.3048)
			(stroke
				(width 0.1)
				(type default)
			)
			(layer "F.Fab")
		)
		(fp_line
			(start 0.120396 0.2794)
			(end -0.12065 0.2794)
			(stroke
				(width 0.1)
				(type default)
			)
			(layer "F.Fab")
		)
		(fp_line
			(start 0.120396 0.3048)
			(end 0.120396 0.2794)
			(stroke
				(width 0.1)
				(type default)
			)
			(layer "F.Fab")
		)
		(fp_line
			(start 0.12065 -0.3048)
			(end 0.67945 -0.3048)
			(stroke
				(width 0.1)
				(type default)
			)
			(layer "F.Fab")
		)
		(fp_line
			(start 0.12065 -0.2794)
			(end 0.12065 -0.3048)
			(stroke
				(width 0.1)
				(type default)
			)
			(layer "F.Fab")
		)
		(fp_line
			(start 0.67945 -0.3048)
			(end 0.67945 0.3048)
			(stroke
				(width 0.1)
				(type default)
			)
			(layer "F.Fab")
		)
		(fp_line
			(start 0.67945 0.3048)
			(end 0.120396 0.3048)
			(stroke
				(width 0.1)
				(type default)
			)
			(layer "F.Fab")
		)
		(pad "1" smd circle
			(at -0.40005 0)
			(size 0 0)
			(layers "F.Cu" "F.Mask" "F.Paste")
			(net "SVID_CLK0_CPU0_R")
		)
		(pad "2" smd circle
			(at 0.40005 0)
			(size 0 0)
			(layers "F.Cu" "F.Mask" "F.Paste")
			(net "SVID_CLK_PVCCIN_CPU0_R")
		)
	)
	(footprint ""
		(layer "F.Cu")
		(at 134.92988 -74.259948 90)
		(property "Reference" "C563"
			(at 0 0 90)
			(layer "F.SilkS")
			(hide yes)
			(effects
				(font
					(size 1.27 1.27)
				)
			)
		)
		(property "Value" ""
			(at 0 0 90)
			(layer "F.Fab")
			(effects
				(font
					(size 1.27 1.27)
				)
			)
		)
		(duplicate_pad_numbers_are_jumpers no)
		(fp_line
			(start 1.524 -0.762)
			(end 1.524 0.762)
			(stroke
				(width 0.1524)
				(type default)
			)
			(layer "F.SilkS")
		)
		(fp_line
			(start -1.524 -0.762)
			(end 1.524 -0.762)
			(stroke
				(width 0.1524)
				(type default)
			)
			(layer "F.SilkS")
		)
		(fp_line
			(start 1.524 0.762)
			(end -1.524 0.762)
			(stroke
				(width 0.1524)
				(type default)
			)
			(layer "F.SilkS")
		)
		(fp_line
			(start -1.524 0.762)
			(end -1.524 -0.762)
			(stroke
				(width 0.1524)
				(type default)
			)
			(layer "F.SilkS")
		)
		(fp_line
			(start 1.1049 -0.724916)
			(end -1.1049 -0.724916)
			(stroke
				(width 0.1)
				(type default)
			)
			(layer "F.Fab")
		)
		(fp_line
			(start -1.1049 -0.724916)
			(end -1.1049 0.724916)
			(stroke
				(width 0.1)
				(type default)
			)
			(layer "F.Fab")
		)
		(fp_line
			(start 1.1049 0.724916)
			(end 1.1049 -0.724916)
			(stroke
				(width 0.1)
				(type default)
			)
			(layer "F.Fab")
		)
		(fp_line
			(start -1.1049 0.724916)
			(end 1.1049 0.724916)
			(stroke
				(width 0.1)
				(type default)
			)
			(layer "F.Fab")
		)
		(pad "1" smd rect
			(at -0.889 0 270)
			(size 1.016 1.27)
			(layers "F.Cu" "F.Mask" "F.Paste")
			(net "P3V3_AUX_BMC_D")
		)
		(pad "2" smd rect
			(at 0.889 0 270)
			(size 1.016 1.27)
			(layers "F.Cu" "F.Mask" "F.Paste")
			(net "GND")
		)
	)
	(footprint ""
		(layer "F.Cu")
		(at 438.256172 -32.173418 90)
		(property "Reference" "PR3837"
			(at 0 0 90)
			(layer "F.SilkS")
			(hide yes)
			(effects
				(font
					(size 1.27 1.27)
				)
			)
		)
		(property "Value" ""
			(at 0 0 90)
			(layer "F.Fab")
			(effects
				(font
					(size 1.27 1.27)
				)
			)
		)
		(duplicate_pad_numbers_are_jumpers no)
		(fp_line
			(start 0.7874 -0.4064)
			(end 0.7874 0.4064)
			(stroke
				(width 0.1524)
				(type default)
			)
			(layer "F.SilkS")
		)
		(fp_line
			(start -0.7874 -0.4064)
			(end 0.7874 -0.4064)
			(stroke
				(width 0.1524)
				(type default)
			)
			(layer "F.SilkS")
		)
		(fp_line
			(start 0.7874 0.4064)
			(end -0.7874 0.4064)
			(stroke
				(width 0.1524)
				(type default)
			)
			(layer "F.SilkS")
		)
		(fp_line
			(start -0.7874 0.4064)
			(end -0.7874 -0.4064)
			(stroke
				(width 0.1524)
				(type default)
			)
			(layer "F.SilkS")
		)
		(fp_line
			(start -0.12065 -0.305054)
			(end -0.12065 -0.2794)
			(stroke
				(width 0.1)
				(type default)
			)
			(layer "F.Fab")
		)
		(fp_line
			(start -0.67945 -0.305054)
			(end -0.12065 -0.305054)
			(stroke
				(width 0.1)
				(type default)
			)
			(layer "F.Fab")
		)
		(fp_line
			(start 0.67945 -0.3048)
			(end 0.67945 0.3048)
			(stroke
				(width 0.1)
				(type default)
			)
			(layer "F.Fab")
		)
		(fp_line
			(start 0.12065 -0.3048)
			(end 0.67945 -0.3048)
			(stroke
				(width 0.1)
				(type default)
			)
			(layer "F.Fab")
		)
		(fp_line
			(start 0.12065 -0.2794)
			(end 0.12065 -0.3048)
			(stroke
				(width 0.1)
				(type default)
			)
			(layer "F.Fab")
		)
		(fp_line
			(start -0.12065 -0.2794)
			(end 0.12065 -0.2794)
			(stroke
				(width 0.1)
				(type default)
			)
			(layer "F.Fab")
		)
		(fp_line
			(start 0.120396 0.2794)
			(end -0.12065 0.2794)
			(stroke
				(width 0.1)
				(type default)
			)
			(layer "F.Fab")
		)
		(fp_line
			(start -0.12065 0.2794)
			(end -0.12065 0.3048)
			(stroke
				(width 0.1)
				(type default)
			)
			(layer "F.Fab")
		)
		(fp_line
			(start 0.67945 0.3048)
			(end 0.120396 0.3048)
			(stroke
				(width 0.1)
				(type default)
			)
			(layer "F.Fab")
		)
		(fp_line
			(start 0.120396 0.3048)
			(end 0.120396 0.2794)
			(stroke
				(width 0.1)
				(type default)
			)
			(layer "F.Fab")
		)
		(fp_line
			(start -0.12065 0.3048)
			(end -0.67945 0.3048)
			(stroke
				(width 0.1)
				(type default)
			)
			(layer "F.Fab")
		)
		(fp_line
			(start -0.67945 0.3048)
			(end -0.67945 -0.305054)
			(stroke
				(width 0.1)
				(type default)
			)
			(layer "F.Fab")
		)
		(pad "1" smd circle
			(at -0.40005 0 90)
			(size 0 0)
			(layers "F.Cu" "F.Mask" "F.Paste")
			(net "P12V_OCP_IMON_1")
		)
		(pad "2" smd circle
			(at 0.40005 0 90)
			(size 0 0)
			(layers "F.Cu" "F.Mask" "F.Paste")
			(net "GND")
		)
	)
)
